# BASEBOARD_FAB2 (Tioga Pass) — schematic netlist excerpt (pin names and nets, part order shuffled) for the footprints in the layout excerpt that follows; sources: Cadence DE-HDL packaged netlist, KiCad conversion of Wiwynn_Tioga_Pass_MB.brd

J6T1  SCONN288_H44441003  SCONN  pkg PIP  page 44
  \12v\(1)  = P12V_NVDIMM_ABC
  VSS(93)  = GND
  DQ(4)  = M_A_DQ<4>
  VSS(92)  = GND
  DQ(0)  = M_A_DQ<0>
  VSS(91)  = GND
  DQS9P  = M_A_DQS_DP<9>
  DQS9N  = M_A_DQS_DN<9>
  VSS(90)  = GND
  DQ(6)  = M_A_DQ<6>
  VSS(89)  = GND
  DQ(2)  = M_A_DQ<2>
  VSS(88)  = GND
  DQ(12)  = M_A_DQ<12>
  VSS(87)  = GND
  DQ(8)  = M_A_DQ<8>
  VSS(86)  = GND
  DQS10P  = M_A_DQS_DP<10>
  DQS10N  = M_A_DQS_DN<10>
  VSS(85)  = GND
  DQ(14)  = M_A_DQ<14>
  VSS(84)  = GND
  DQ(10)  = M_A_DQ<10>
  VSS(83)  = GND
  DQ(20)  = M_A_DQ<20>
  VSS(82)  = GND
  DQ(16)  = M_A_DQ<16>
  VSS(81)  = GND
  DQS11P  = M_A_DQS_DP<11>
  DQS11N  = M_A_DQS_DN<11>
  VSS(80)  = GND
  DQ(22)  = M_A_DQ<22>
  VSS(79)  = GND
  DQ(18)  = M_A_DQ<18>
  VSS(78)  = GND
  DQ(28)  = M_A_DQ<28>
  VSS(77)  = GND
  DQ(24)  = M_A_DQ<24>
  VSS(76)  = GND
  DQS12P  = M_A_DQS_DP<12>
  DQS12N  = M_A_DQS_DN<12>
  VSS(75)  = GND
  DQ(30)  = M_A_DQ<30>
  VSS(74)  = GND
  DQ(26)  = M_A_DQ<26>
  VSS(73)  = GND
  CB(4)  = M_A_ECC<4>
  VSS(72)  = GND
  CB(0)  = M_A_ECC<0>
  VSS(71)  = GND
  DQS17P  = M_A_DQS_DP<17>
  DQS17N  = M_A_DQS_DN<17>
  VSS(70)  = GND
  CB(6)  = M_A_ECC<6>
  VSS(69)  = GND
  CB(2)  = M_A_ECC<2>
  VSS(68)  = GND
  RESET_N  = M_ABC_RST_N
  VDD(25)  = PVDDQ_ABC
  CKE(0)  = M_A_CKE<2>
  VDD(24)  = PVDDQ_ABC
  ACT_N  = M_A_ACT_N
  BG(0)  = M_A_BG<0>
  VDD(23)  = PVDDQ_ABC
  A12  = M_A_MA<12>
  A9  = M_A_MA<9>
  VDD(22)  = PVDDQ_ABC
  A8  = M_A_MA<8>
  A6  = M_A_MA<6>
  VDD(21)  = PVDDQ_ABC
  A3  = M_A_MA<3>
  A1  = M_A_MA<1>
  VDD(20)  = PVDDQ_ABC
  CK0P  = M_A_CLK_DP<2>
  CK0N  = M_A_CLK_DN<2>
  VDD(19)  = PVDDQ_ABC
  VTT(1)  = PVTT_ABC
  EVENT_N  = FM_DIMM_EVENT_COD_N
  A0  = M_A_MA<0>
  VDD(18)  = PVDDQ_ABC
  BA(0)  = M_A_BA<0>
  A16_RAS_N  = M_A_MA<16>
  VDD(17)  = PVDDQ_ABC
  S0_N  = M_A_CS_N<4>
  VDD(16)  = PVDDQ_ABC
  A15_CAS_N  = M_A_MA<15>
  ODT(0)  = M_A_ODT<2>
  VDD(15)  = PVDDQ_ABC
  S1_N  = M_A_CS_N<5>
  VDD(14)  = PVDDQ_ABC
  ODT(1)  = M_A_ODT<3>
  VDD(13)  = PVDDQ_ABC
  S2_N_C(0)  = M_A_CS_N<6>
  VSS(67)  = GND
  DQ(36)  = M_A_DQ<36>
  VSS(66)  = GND
  DQ(32)  = M_A_DQ<32>
  VSS(65)  = GND
  DQS13P  = M_A_DQS_DP<13>
  DQS13N  = M_A_DQS_DN<13>
  VSS(64)  = GND
  DQ(38)  = M_A_DQ<38>
  VSS(63)  = GND
  DQ(34)  = M_A_DQ<34>
  VSS(62)  = GND
  DQ(44)  = M_A_DQ<44>
  VSS(61)  = GND
  DQ(40)  = M_A_DQ<40>
  VSS(60)  = GND
  DQS14P  = M_A_DQS_DP<14>
  DQS14N  = M_A_DQS_DN<14>
  VSS(59)  = GND
  DQ(46)  = M_A_DQ<46>
  VSS(58)  = GND
  DQ(42)  = M_A_DQ<42>
  VSS(57)  = GND
  DQ(52)  = M_A_DQ<52>
  VSS(56)  = GND
  DQ(48)  = M_A_DQ<48>
  VSS(55)  = GND
  DQS15P  = M_A_DQS_DP<15>
  DQS15N  = M_A_DQS_DN<15>
  VSS(54)  = GND
  DQ(54)  = M_A_DQ<54>
  VSS(53)  = GND
  DQ(50)  = M_A_DQ<50>
  VSS(52)  = GND
  DQ(60)  = M_A_DQ<60>
  VSS(51)  = GND
  DQ(56)  = M_A_DQ<56>
  VSS(50)  = GND
  DQS16P  = M_A_DQS_DP<16>
  DQS16N  = M_A_DQS_DN<16>
  VSS(49)  = GND
  DQ(62)  = M_A_DQ<62>
  VSS(48)  = GND
  DQ(58)  = M_A_DQ<58>
  VSS(47)  = GND
  SA(0)  = PVPP_ABC
  SA(1)  = GND
  SCL  = SMB_DDR_ABC_VPP_SCL
  VPP(4)  = PVPP_ABC
  VPP(3)  = PVPP_ABC
  RFU(2)  = TP_CH_A_DIMM_A1_RFU_2
  \12v\(0)  = P12V_NVDIMM_ABC
  VREFCA  = M_A_VREF
  VSS(46)  = GND
  DQ(5)  = M_A_DQ<5>
  VSS(45)  = GND
  DQ(1)  = M_A_DQ<1>
  VSS(44)  = GND
  DQS0N  = M_A_DQS_DN<0>
  DQS0P  = M_A_DQS_DP<0>
  VSS(43)  = GND
  DQ(7)  = M_A_DQ<7>
  VSS(42)  = GND
  DQ(3)  = M_A_DQ<3>
  VSS(41)  = GND
  DQ(13)  = M_A_DQ<13>
  VSS(40)  = GND
  DQ(9)  = M_A_DQ<9>
  VSS(39)  = GND
  DQS1N  = M_A_DQS_DN<1>
  DQS1P  = M_A_DQS_DP<1>
  VSS(38)  = GND
  DQ(15)  = M_A_DQ<15>
  VSS(37)  = GND
  DQ(11)  = M_A_DQ<11>
  VSS(36)  = GND
  DQ(21)  = M_A_DQ<21>
  VSS(35)  = GND
  DQ(17)  = M_A_DQ<17>
  VSS(34)  = GND
  DQS2N  = M_A_DQS_DN<2>
  DQS2P  = M_A_DQS_DP<2>
  VSS(33)  = GND
  DQ(23)  = M_A_DQ<23>
  VSS(32)  = GND
  DQ(19)  = M_A_DQ<19>
  VSS(31)  = GND
  DQ(29)  = M_A_DQ<29>
  VSS(30)  = GND
  DQ(25)  = M_A_DQ<25>
  VSS(29)  = GND
  DQS3N  = M_A_DQS_DN<3>
  DQS3P  = M_A_DQS_DP<3>
  VSS(28)  = GND
  DQ(31)  = M_A_DQ<31>
  VSS(27)  = GND
  DQ(27)  = M_A_DQ<27>
  VSS(26)  = GND
  CB(5)  = M_A_ECC<5>
  VSS(25)  = GND
  CB(1)  = M_A_ECC<1>
  VSS(24)  = GND
  DQS8N  = M_A_DQS_DN<8>
  DQS8P  = M_A_DQS_DP<8>
  VSS(23)  = GND
  CB(7)  = M_A_ECC<7>
  VSS(22)  = GND
  CB(3)  = M_A_ECC<3>
  VSS(21)  = GND
  CKE(1)  = M_A_CKE<3>
  VDD(12)  = PVDDQ_ABC
  RFU(0)  = TP_CH_A_DIMM_A1_RFU_0
  VDD(11)  = PVDDQ_ABC
  BG(1)  = M_A_BG<1>
  ALERT_N  = M_A_ALERT_N
  VDD(10)  = PVDDQ_ABC
  A11  = M_A_MA<11>
  A7  = M_A_MA<7>
  VDD(9)  = PVDDQ_ABC
  A5  = M_A_MA<5>
  A4  = M_A_MA<4>
  VDD(8)  = PVDDQ_ABC
  A2  = M_A_MA<2>
  VDD(7)  = PVDDQ_ABC
  CK1P  = M_A_CLK_DP<3>
  CK1N  = M_A_CLK_DN<3>
  VDD(6)  = PVDDQ_ABC
  VTT(0)  = PVTT_ABC
  PAR  = M_A_PAR
  VDD(5)  = PVDDQ_ABC
  BA(1)  = M_A_BA<1>
  A10  = M_A_MA<10>
  VDD(4)  = PVDDQ_ABC
  RFU(1)  = TP_CH_A_DIMM_A1_RFU_1
  A14_WE_N  = M_A_MA<14>
  VDD(3)  = PVDDQ_ABC
  SAVE_N_NC  = FM_ADR_COMPLETE_ABC_N
  VDD(2)  = PVDDQ_ABC
  A13  = M_A_MA<13>
  VDD(1)  = PVDDQ_ABC
  A17  = M_A_MA<17>
  C(2)  = M_A_C<2>
  VDD(0)  = PVDDQ_ABC
  S3_N_C(1)  = M_A_CS_N<7>
  SA(2)  = GND
  VSS(20)  = GND
  DQ(37)  = M_A_DQ<37>
  VSS(19)  = GND
  DQ(33)  = M_A_DQ<33>
  VSS(18)  = GND
  DQS4N  = M_A_DQS_DN<4>
  DQS4P  = M_A_DQS_DP<4>
  VSS(17)  = GND
  DQ(39)  = M_A_DQ<39>
  VSS(16)  = GND
  DQ(35)  = M_A_DQ<35>
  VSS(15)  = GND
  DQ(45)  = M_A_DQ<45>
  VSS(14)  = GND
  DQ(41)  = M_A_DQ<41>
  VSS(13)  = GND
  DQS5N  = M_A_DQS_DN<5>
  DQS5P  = M_A_DQS_DP<5>
  VSS(12)  = GND
  DQ(47)  = M_A_DQ<47>
  VSS(11)  = GND
  DQ(43)  = M_A_DQ<43>
  VSS(10)  = GND
  DQ(53)  = M_A_DQ<53>
  VSS(9)  = GND
  DQ(49)  = M_A_DQ<49>
  VSS(8)  = GND
  DQS6N  = M_A_DQS_DN<6>
  DQS6P  = M_A_DQS_DP<6>
  VSS(7)  = GND
  DQ(55)  = M_A_DQ<55>
  VSS(6)  = GND
  DQ(51)  = M_A_DQ<51>
  VSS(5)  = GND
  DQ(61)  = M_A_DQ<61>
  VSS(4)  = GND
  DQ(57)  = M_A_DQ<57>
  VSS(3)  = GND
  DQS7N  = M_A_DQS_DN<7>
  DQS7P  = M_A_DQS_DP<7>
  VSS(2)  = GND
  DQ(63)  = M_A_DQ<63>
  VSS(1)  = GND
  DQ(59)  = M_A_DQ<59>
  VSS(0)  = GND
  VDDSPD  = PVPP_ABC
  SDA  = SMB_DDR_ABC_VPP_SDA
  VPP(1)  = PVPP_ABC
  VPP(0)  = PVPP_ABC
  VPP(2)  = PVPP_ABC

(kicad_pcb
	(version 20260206)
	(generator "pcbnew")
	(generator_version "10.0")
	(general
		(thickness 1.6)
		(legacy_teardrops no)
	)
	(paper "A4")
	(title_block
		(title "Wiwynn_Tioga_Pass_MB.brd")
		(comment 1 "Tioga Pass / footprint 3283 of 4770 (J6T1), pads 250-291 of 291")
	)
	(layers
		(0 "F.Cu" signal "TOP")
		(4 "In1.Cu" signal "L2GND")
		(6 "In2.Cu" signal "L3")
		(8 "In3.Cu" signal "L4GND")
		(10 "In4.Cu" signal "L5")
		(12 "In5.Cu" signal "L6GND")
		(14 "In6.Cu" signal "L7VCC")
		(16 "In7.Cu" signal "L8VCC")
		(18 "In8.Cu" signal "L9GND")
		(20 "In9.Cu" signal "L10")
		(22 "In10.Cu" signal "L11GND")
		(24 "In11.Cu" signal "L12")
		(26 "In12.Cu" signal "L13GND")
		(2 "B.Cu" signal "BOTTOM")
		(9 "F.Adhes" user "F.Adhesive")
		(11 "B.Adhes" user "B.Adhesive")
		(13 "F.Paste" user "Package Geometry/Pastemask Top")
		(15 "B.Paste" user "Package Geometry/Pastemask Bottom")
		(5 "F.SilkS" user "Ref Des/Silkscreen Top")
		(7 "B.SilkS" user "Ref Des/Silkscreen Bottom")
		(1 "F.Mask" user "Board Geometry/Soldermask Top")
		(3 "B.Mask" user "Board Geometry/Soldermask Bottom")
		(17 "Dwgs.User" user "User.Drawings")
		(19 "Cmts.User" user "User.Comments")
		(21 "Eco1.User" user "User.Eco1")
		(23 "Eco2.User" user "User.Eco2")
		(25 "Edge.Cuts" user "Board Geometry/Outline")
		(27 "Margin" user)
		(31 "F.CrtYd" user "Package Geometry/Place Bound Top")
		(29 "B.CrtYd" user "Package Geometry/Place Bound Bottom")
		(35 "F.Fab" user "Ref Des/Assembly Top")
		(33 "B.Fab" user "Ref Des/Assembly Bottom")
	)
	(footprint ""
		(layer "B.Cu")
		(at 194.700398 -24.824182 90)
		(property "Reference" "J6T1"
			(at 2.200148 39.23411 0)
			(unlocked yes)
			(layer "B.SilkS")
			(effects
				(font
					(size 0.7874 0.5842)
					(thickness 0.1524)
				)
				(justify left mirror)
			)
		)
		(property "Value" ""
			(at 0 0 90)
			(layer "B.Fab")
			(effects
				(font
					(size 1.27 1.27)
				)
				(justify mirror)
			)
		)
		(duplicate_pad_numbers_are_jumpers no)
		(pad "247" smd rect
			(at -4.59994 91.799918 270)
			(size 1.8034 0.508)
			(layers "B.Cu" "B.Mask" "B.Paste")
			(net "M_A_DQ<39>")
		)
		(pad "248" smd rect
			(at -4.59994 92.650056 270)
			(size 1.8034 0.508)
			(layers "B.Cu" "B.Mask" "B.Paste")
			(net "GND")
		)
		(pad "249" smd rect
			(at -4.59994 93.49994 270)
			(size 1.8034 0.508)
			(layers "B.Cu" "B.Mask" "B.Paste")
			(net "M_A_DQ<35>")
		)
		(pad "250" smd rect
			(at -4.59994 94.350078 270)
			(size 1.8034 0.508)
			(layers "B.Cu" "B.Mask" "B.Paste")
			(net "GND")
		)
		(pad "251" smd rect
			(at -4.59994 95.199962 270)
			(size 1.8034 0.508)
			(layers "B.Cu" "B.Mask" "B.Paste")
			(net "M_A_DQ<45>")
		)
		(pad "252" smd rect
			(at -4.59994 96.0501 270)
			(size 1.8034 0.508)
			(layers "B.Cu" "B.Mask" "B.Paste")
			(net "GND")
		)
		(pad "253" smd rect
			(at -4.59994 96.899984 270)
			(size 1.8034 0.508)
			(layers "B.Cu" "B.Mask" "B.Paste")
			(net "M_A_DQ<41>")
		)
		(pad "254" smd rect
			(at -4.59994 97.750122 270)
			(size 1.8034 0.508)
			(layers "B.Cu" "B.Mask" "B.Paste")
			(net "GND")
		)
		(pad "255" smd rect
			(at -4.59994 98.600006 270)
			(size 1.8034 0.508)
			(layers "B.Cu" "B.Mask" "B.Paste")
			(net "M_A_DQS_DN<5>")
		)
		(pad "256" smd rect
			(at -4.59994 99.44989 270)
			(size 1.8034 0.508)
			(layers "B.Cu" "B.Mask" "B.Paste")
			(net "M_A_DQS_DP<5>")
		)
		(pad "257" smd rect
			(at -4.59994 100.300028 270)
			(size 1.8034 0.508)
			(layers "B.Cu" "B.Mask" "B.Paste")
			(net "GND")
		)
		(pad "258" smd rect
			(at -4.59994 101.149912 270)
			(size 1.8034 0.508)
			(layers "B.Cu" "B.Mask" "B.Paste")
			(net "M_A_DQ<47>")
		)
		(pad "259" smd rect
			(at -4.59994 102.00005 270)
			(size 1.8034 0.508)
			(layers "B.Cu" "B.Mask" "B.Paste")
			(net "GND")
		)
		(pad "260" smd rect
			(at -4.59994 102.849934 270)
			(size 1.8034 0.508)
			(layers "B.Cu" "B.Mask" "B.Paste")
			(net "M_A_DQ<43>")
		)
		(pad "261" smd rect
			(at -4.59994 103.700072 270)
			(size 1.8034 0.508)
			(layers "B.Cu" "B.Mask" "B.Paste")
			(net "GND")
		)
		(pad "262" smd rect
			(at -4.59994 104.549956 270)
			(size 1.8034 0.508)
			(layers "B.Cu" "B.Mask" "B.Paste")
			(net "M_A_DQ<53>")
		)
		(pad "263" smd rect
			(at -4.59994 105.400094 270)
			(size 1.8034 0.508)
			(layers "B.Cu" "B.Mask" "B.Paste")
			(net "GND")
		)
		(pad "264" smd rect
			(at -4.59994 106.249978 270)
			(size 1.8034 0.508)
			(layers "B.Cu" "B.Mask" "B.Paste")
			(net "M_A_DQ<49>")
		)
		(pad "265" smd rect
			(at -4.59994 107.100116 270)
			(size 1.8034 0.508)
			(layers "B.Cu" "B.Mask" "B.Paste")
			(net "GND")
		)
		(pad "266" smd rect
			(at -4.59994 107.95 270)
			(size 1.8034 0.508)
			(layers "B.Cu" "B.Mask" "B.Paste")
			(net "M_A_DQS_DN<6>")
		)
		(pad "267" smd rect
			(at -4.59994 108.799884 270)
			(size 1.8034 0.508)
			(layers "B.Cu" "B.Mask" "B.Paste")
			(net "M_A_DQS_DP<6>")
		)
		(pad "268" smd rect
			(at -4.59994 109.650022 270)
			(size 1.8034 0.508)
			(layers "B.Cu" "B.Mask" "B.Paste")
			(net "GND")
		)
		(pad "269" smd rect
			(at -4.59994 110.499906 270)
			(size 1.8034 0.508)
			(layers "B.Cu" "B.Mask" "B.Paste")
			(net "M_A_DQ<55>")
		)
		(pad "270" smd rect
			(at -4.59994 111.350044 270)
			(size 1.8034 0.508)
			(layers "B.Cu" "B.Mask" "B.Paste")
			(net "GND")
		)
		(pad "271" smd rect
			(at -4.59994 112.199928 270)
			(size 1.8034 0.508)
			(layers "B.Cu" "B.Mask" "B.Paste")
			(net "M_A_DQ<51>")
		)
		(pad "272" smd rect
			(at -4.59994 113.050066 270)
			(size 1.8034 0.508)
			(layers "B.Cu" "B.Mask" "B.Paste")
			(net "GND")
		)
		(pad "273" smd rect
			(at -4.59994 113.89995 270)
			(size 1.8034 0.508)
			(layers "B.Cu" "B.Mask" "B.Paste")
			(net "M_A_DQ<61>")
		)
		(pad "274" smd rect
			(at -4.59994 114.750088 270)
			(size 1.8034 0.508)
			(layers "B.Cu" "B.Mask" "B.Paste")
			(net "GND")
		)
		(pad "275" smd rect
			(at -4.59994 115.599972 270)
			(size 1.8034 0.508)
			(layers "B.Cu" "B.Mask" "B.Paste")
			(net "M_A_DQ<57>")
		)
		(pad "276" smd rect
			(at -4.59994 116.45011 270)
			(size 1.8034 0.508)
			(layers "B.Cu" "B.Mask" "B.Paste")
			(net "GND")
		)
		(pad "277" smd rect
			(at -4.59994 117.299994 270)
			(size 1.8034 0.508)
			(layers "B.Cu" "B.Mask" "B.Paste")
			(net "M_A_DQS_DN<7>")
		)
		(pad "278" smd rect
			(at -4.59994 118.149878 270)
			(size 1.8034 0.508)
			(layers "B.Cu" "B.Mask" "B.Paste")
			(net "M_A_DQS_DP<7>")
		)
		(pad "279" smd rect
			(at -4.59994 119.000016 270)
			(size 1.8034 0.508)
			(layers "B.Cu" "B.Mask" "B.Paste")
			(net "GND")
		)
		(pad "280" smd rect
			(at -4.59994 119.8499 270)
			(size 1.8034 0.508)
			(layers "B.Cu" "B.Mask" "B.Paste")
			(net "M_A_DQ<63>")
		)
		(pad "281" smd rect
			(at -4.59994 120.700038 270)
			(size 1.8034 0.508)
			(layers "B.Cu" "B.Mask" "B.Paste")
			(net "GND")
		)
		(pad "282" smd rect
			(at -4.59994 121.549922 270)
			(size 1.8034 0.508)
			(layers "B.Cu" "B.Mask" "B.Paste")
			(net "M_A_DQ<59>")
		)
		(pad "283" smd rect
			(at -4.59994 122.40006 270)
			(size 1.8034 0.508)
			(layers "B.Cu" "B.Mask" "B.Paste")
			(net "GND")
		)
		(pad "284" smd rect
			(at -4.59994 123.249944 270)
			(size 1.8034 0.508)
			(layers "B.Cu" "B.Mask" "B.Paste")
			(net "PVPP_ABC")
		)
		(pad "285" smd rect
			(at -4.59994 124.100082 270)
			(size 1.8034 0.508)
			(layers "B.Cu" "B.Mask" "B.Paste")
			(net "SMB_DDR_ABC_VPP_SDA")
		)
		(pad "286" smd rect
			(at -4.59994 124.949966 270)
			(size 1.8034 0.508)
			(layers "B.Cu" "B.Mask" "B.Paste")
			(net "PVPP_ABC")
		)
		(pad "287" smd rect
			(at -4.59994 125.800104 270)
			(size 1.8034 0.508)
			(layers "B.Cu" "B.Mask" "B.Paste")
			(net "PVPP_ABC")
		)
		(pad "288" smd rect
			(at -4.59994 126.649988 270)
			(size 1.8034 0.508)
			(layers "B.Cu" "B.Mask" "B.Paste")
			(net "PVPP_ABC")
		)
	)
)
